(kicad_pcb
	(version 20211014)
	(generator pcbnew)
	(general
    (thickness 1.6)
  )
	(paper "A4")
	(title_block
    (title "SI test board")
    (rev "1.0.1")
    (company "Antmicro")
		(comment 9 "footprints 19-23 of 27")
	)
	(layers
    (0 "F.Cu" signal)
    (1 "In1.Cu" signal)
    (2 "In2.Cu" signal)
    (31 "B.Cu" signal)
    (32 "B.Adhes" user "B.Adhesive")
    (33 "F.Adhes" user "F.Adhesive")
    (34 "B.Paste" user)
    (35 "F.Paste" user)
    (36 "B.SilkS" user "B.Silkscreen")
    (37 "F.SilkS" user "F.Silkscreen")
    (38 "B.Mask" user)
    (39 "F.Mask" user)
    (40 "Dwgs.User" user "User.Drawings")
    (41 "Cmts.User" user "User.Comments")
    (42 "Eco1.User" user "User.Eco1")
    (43 "Eco2.User" user "User.Eco2")
    (44 "Edge.Cuts" user)
    (45 "Margin" user)
    (46 "B.CrtYd" user "B.Courtyard")
    (47 "F.CrtYd" user "F.Courtyard")
    (48 "B.Fab" user)
    (49 "F.Fab" user)
  )
	(footprint "si-simulation-test-board-footprints:RF_SMA_BoardEdge_RF2-143-T-17-50-G" (layer "F.Cu")
    (tedit 64FEFFC5)
    (at 91.37 127.614499 90)
    (descr "RF SMA SMD board edge connector")
    (property "Author" "Antmicro")
    (property "License" "Apache-2.0")
    (property "MPN" "RF2-143-T-17-50-G")
    (property "Manufacturer" "ADAM TECH")
    (property "Sheetfile" "si-simulation-test-board.kicad_sch")
    (property "Sheetname" "")
    (attr smd)
    (fp_text reference "J19" (at -4.5 6.88 180) (layer "F.SilkS")
      (effects (font (size 0.7 0.7) (thickness 0.15)) (justify left bottom))
    )
    (fp_text value "Conn_SMA_RF2-143-T-17-50-G" (at 0 9.24 90) (layer "F.Fab")
      (effects (font (size 0.7 0.7) (thickness 0.15)) (justify left bottom))
    )
    (fp_text user "License: Apache-2.0" (at -4.5 12.44 90) (layer "F.Fab") hide
      (effects (font (size 0.7 0.7) (thickness 0.15)) (justify left bottom))
    )
    (fp_text user "Author: Antmicro" (at -4.5 11.24 90) (layer "F.Fab") hide
      (effects (font (size 0.7 0.7) (thickness 0.15)) (justify left bottom))
    )
    (fp_text user "${REFERENCE}" (at -4.5 13.64 90) (layer "F.Fab") hide
      (effects (font (size 0.7 0.7) (thickness 0.15)) (justify left bottom))
    )
    (fp_rect (start -3.995 -7.53) (end 3.995 7.53) (layer "B.CrtYd") (width 0.05) (fill none))
    (fp_rect (start -3.995 -7.53) (end 3.995 7.53) (layer "F.CrtYd") (width 0.05) (fill none))
    (fp_line (start 2.375 6.455) (end 2.375 2.678) (layer "F.Fab") (width 0.15))
    (fp_line (start 2.65 -6.375) (end -2.65 -6.375) (layer "F.Fab") (width 0.15))
    (fp_line (start -0.38 2.654) (end -0.38 6.455) (layer "F.Fab") (width 0.15))
    (fp_line (start 3.174 1.504) (end -3.174 1.504) (layer "F.Fab") (width 0.15))
    (fp_line (start -2.65 -6.375) (end -2.65 1.504) (layer "F.Fab") (width 0.15))
    (fp_line (start -2.375 2.678) (end -2.375 6.455) (layer "F.Fab") (width 0.15))
    (fp_line (start 0.38 2.654) (end 0.375 6.455) (layer "F.Fab") (width 0.15))
    (fp_line (start 3.174 6.455) (end 2.375 6.455) (layer "F.Fab") (width 0.15))
    (fp_line (start 3.174 2.654) (end -3.15 2.654) (layer "F.Fab") (width 0.15))
    (fp_line (start -2.375 6.455) (end -3.174 6.455) (layer "F.Fab") (width 0.15))
    (fp_line (start 3.174 6.455) (end 3.174 1.504) (layer "F.Fab") (width 0.15))
    (fp_line (start 0.375 6.455) (end -0.38 6.455) (layer "F.Fab") (width 0.15))
    (fp_line (start -3.174 6.455) (end -3.174 1.504) (layer "F.Fab") (width 0.15))
    (fp_line (start 2.65 -6.375) (end 2.65 1.504) (layer "F.Fab") (width 0.15))
    (pad "1" smd rect (at 0.007 4.955 90) (size 2.29 4.191) (layers "F.Cu" "F.Paste" "F.Mask")
      (net 2 "GND") (pinfunction "1") (pintype "passive"))
    (pad "2" smd rect (at 2.975 4.955 90) (size 1.45 4.191) (layers "F.Cu" "F.Paste" "F.Mask")
      (net 2 "GND") (pinfunction "2") (pintype "passive"))
    (pad "2" smd rect (at 2.975 4.955 90) (size 1.45 4.191) (layers "B.Cu" "B.Paste" "B.Mask")
      (net 2 "GND") (pinfunction "2") (pintype "passive"))
    (pad "2" smd rect (at -2.975 4.955 90) (size 1.45 4.191) (layers "F.Cu" "F.Paste" "F.Mask")
      (net 2 "GND") (pinfunction "2") (pintype "passive"))
    (pad "2" smd rect (at -2.975 4.955 90) (size 1.45 4.191) (layers "B.Cu" "B.Paste" "B.Mask")
      (net 2 "GND") (pinfunction "2") (pintype "passive"))
  )
	(footprint "si-simulation-test-board-footprints:RF_SMA_BoardEdge_RF2-143-T-17-50-G" (layer "F.Cu")
    (tedit 64FEFFC5)
    (at 146.63 56.0005 -90)
    (descr "RF SMA SMD board edge connector")
    (property "Author" "Antmicro")
    (property "License" "Apache-2.0")
    (property "MPN" "RF2-143-T-17-50-G")
    (property "Manufacturer" "ADAM TECH")
    (property "Sheetfile" "si-simulation-test-board.kicad_sch")
    (property "Sheetname" "")
    (attr smd)
    (fp_text reference "J5" (at -4.5 6.88) (layer "F.SilkS")
      (effects (font (size 0.7 0.7) (thickness 0.15)) (justify left bottom))
    )
    (fp_text value "Conn_SMA_RF2-143-T-17-50-G" (at 0 9.24 -90) (layer "F.Fab")
      (effects (font (size 0.7 0.7) (thickness 0.15)) (justify left bottom))
    )
    (fp_text user "Author: Antmicro" (at -4.5 11.24 -90) (layer "F.Fab") hide
      (effects (font (size 0.7 0.7) (thickness 0.15)) (justify left bottom))
    )
    (fp_text user "License: Apache-2.0" (at -4.5 12.44 -90) (layer "F.Fab") hide
      (effects (font (size 0.7 0.7) (thickness 0.15)) (justify left bottom))
    )
    (fp_text user "${REFERENCE}" (at -4.5 13.64 -90) (layer "F.Fab") hide
      (effects (font (size 0.7 0.7) (thickness 0.15)) (justify left bottom))
    )
    (fp_rect (start -3.995 -7.53) (end 3.995 7.53) (layer "B.CrtYd") (width 0.05) (fill none))
    (fp_rect (start -3.995 -7.53) (end 3.995 7.53) (layer "F.CrtYd") (width 0.05) (fill none))
    (fp_line (start -3.174 6.455) (end -3.174 1.504) (layer "F.Fab") (width 0.15))
    (fp_line (start 0.38 2.654) (end 0.375 6.455) (layer "F.Fab") (width 0.15))
    (fp_line (start 2.65 -6.375) (end -2.65 -6.375) (layer "F.Fab") (width 0.15))
    (fp_line (start 3.174 1.504) (end -3.174 1.504) (layer "F.Fab") (width 0.15))
    (fp_line (start -2.65 -6.375) (end -2.65 1.504) (layer "F.Fab") (width 0.15))
    (fp_line (start -2.375 6.455) (end -3.174 6.455) (layer "F.Fab") (width 0.15))
    (fp_line (start -2.375 2.678) (end -2.375 6.455) (layer "F.Fab") (width 0.15))
    (fp_line (start 2.65 -6.375) (end 2.65 1.504) (layer "F.Fab") (width 0.15))
    (fp_line (start 0.375 6.455) (end -0.38 6.455) (layer "F.Fab") (width 0.15))
    (fp_line (start 2.375 6.455) (end 2.375 2.678) (layer "F.Fab") (width 0.15))
    (fp_line (start 3.174 6.455) (end 3.174 1.504) (layer "F.Fab") (width 0.15))
    (fp_line (start 3.174 2.654) (end -3.15 2.654) (layer "F.Fab") (width 0.15))
    (fp_line (start -0.38 2.654) (end -0.38 6.455) (layer "F.Fab") (width 0.15))
    (fp_line (start 3.174 6.455) (end 2.375 6.455) (layer "F.Fab") (width 0.15))
    (pad "1" smd rect (at 0.007 4.955 270) (size 2.29 4.191) (layers "F.Cu" "F.Paste" "F.Mask")
      (net 4 "Net-(AE1-Pad1)") (pinfunction "1") (pintype "passive"))
    (pad "2" smd rect (at 2.975 4.955 270) (size 1.45 4.191) (layers "B.Cu" "B.Paste" "B.Mask")
      (net 2 "GND") (pinfunction "2") (pintype "passive"))
    (pad "2" smd rect (at -2.975 4.955 270) (size 1.45 4.191) (layers "B.Cu" "B.Paste" "B.Mask")
      (net 2 "GND") (pinfunction "2") (pintype "passive"))
    (pad "2" smd rect (at -2.975 4.955 270) (size 1.45 4.191) (layers "F.Cu" "F.Paste" "F.Mask")
      (net 2 "GND") (pinfunction "2") (pintype "passive"))
    (pad "2" smd rect (at 2.975 4.955 270) (size 1.45 4.191) (layers "F.Cu" "F.Paste" "F.Mask")
      (net 2 "GND") (pinfunction "2") (pintype "passive"))
  )
	(footprint "si-simulation-test-board-footprints:RF_SMA_BoardEdge_RF2-143-T-17-50-G" (layer "F.Cu")
    (tedit 64FEFFC5)
    (at 91.32 55.999499 90)
    (descr "RF SMA SMD board edge connector")
    (property "Author" "Antmicro")
    (property "License" "Apache-2.0")
    (property "MPN" "RF2-143-T-17-50-G")
    (property "Manufacturer" "ADAM TECH")
    (property "Sheetfile" "si-simulation-test-board.kicad_sch")
    (property "Sheetname" "")
    (attr smd)
    (fp_text reference "J6" (at -4.5 6.88 180) (layer "F.SilkS")
      (effects (font (size 0.7 0.7) (thickness 0.15)) (justify left bottom))
    )
    (fp_text value "Conn_SMA_RF2-143-T-17-50-G" (at 0 9.24 90) (layer "F.Fab")
      (effects (font (size 0.7 0.7) (thickness 0.15)) (justify left bottom))
    )
    (fp_text user "${REFERENCE}" (at -4.5 13.64 90) (layer "F.Fab") hide
      (effects (font (size 0.7 0.7) (thickness 0.15)) (justify left bottom))
    )
    (fp_text user "Author: Antmicro" (at -4.5 11.24 90) (layer "F.Fab") hide
      (effects (font (size 0.7 0.7) (thickness 0.15)) (justify left bottom))
    )
    (fp_text user "License: Apache-2.0" (at -4.5 12.44 90) (layer "F.Fab") hide
      (effects (font (size 0.7 0.7) (thickness 0.15)) (justify left bottom))
    )
    (fp_rect (start -3.995 -7.53) (end 3.995 7.53) (layer "B.CrtYd") (width 0.05) (fill none))
    (fp_rect (start -3.995 -7.53) (end 3.995 7.53) (layer "F.CrtYd") (width 0.05) (fill none))
    (fp_line (start -3.174 6.455) (end -3.174 1.504) (layer "F.Fab") (width 0.15))
    (fp_line (start -0.38 2.654) (end -0.38 6.455) (layer "F.Fab") (width 0.15))
    (fp_line (start 3.174 2.654) (end -3.15 2.654) (layer "F.Fab") (width 0.15))
    (fp_line (start -2.65 -6.375) (end -2.65 1.504) (layer "F.Fab") (width 0.15))
    (fp_line (start 3.174 6.455) (end 3.174 1.504) (layer "F.Fab") (width 0.15))
    (fp_line (start 0.375 6.455) (end -0.38 6.455) (layer "F.Fab") (width 0.15))
    (fp_line (start 2.65 -6.375) (end 2.65 1.504) (layer "F.Fab") (width 0.15))
    (fp_line (start 0.38 2.654) (end 0.375 6.455) (layer "F.Fab") (width 0.15))
    (fp_line (start 2.375 6.455) (end 2.375 2.678) (layer "F.Fab") (width 0.15))
    (fp_line (start 2.65 -6.375) (end -2.65 -6.375) (layer "F.Fab") (width 0.15))
    (fp_line (start -2.375 2.678) (end -2.375 6.455) (layer "F.Fab") (width 0.15))
    (fp_line (start -2.375 6.455) (end -3.174 6.455) (layer "F.Fab") (width 0.15))
    (fp_line (start 3.174 1.504) (end -3.174 1.504) (layer "F.Fab") (width 0.15))
    (fp_line (start 3.174 6.455) (end 2.375 6.455) (layer "F.Fab") (width 0.15))
    (pad "1" smd rect (at 0.007 4.955 90) (size 2.29 4.191) (layers "F.Cu" "F.Paste" "F.Mask")
      (net 11 "Net-(J6-Pad1)") (pinfunction "1") (pintype "passive"))
    (pad "2" smd rect (at 2.975 4.955 90) (size 1.45 4.191) (layers "F.Cu" "F.Paste" "F.Mask")
      (net 2 "GND") (pinfunction "2") (pintype "passive"))
    (pad "2" smd rect (at -2.975 4.955 90) (size 1.45 4.191) (layers "F.Cu" "F.Paste" "F.Mask")
      (net 2 "GND") (pinfunction "2") (pintype "passive"))
    (pad "2" smd rect (at -2.975 4.955 90) (size 1.45 4.191) (layers "B.Cu" "B.Paste" "B.Mask")
      (net 2 "GND") (pinfunction "2") (pintype "passive"))
    (pad "2" smd rect (at 2.975 4.955 90) (size 1.45 4.191) (layers "B.Cu" "B.Paste" "B.Mask")
      (net 2 "GND") (pinfunction "2") (pintype "passive"))
  )
	(footprint "si-simulation-test-board-footprints:RF_SMA_BoardEdge_RF2-143-T-17-50-G" (layer "F.Cu")
    (tedit 64FEFFC5)
    (at 91.37 147.614499 90)
    (descr "RF SMA SMD board edge connector")
    (property "Author" "Antmicro")
    (property "License" "Apache-2.0")
    (property "MPN" "RF2-143-T-17-50-G")
    (property "Manufacturer" "ADAM TECH")
    (property "Sheetfile" "si-simulation-test-board.kicad_sch")
    (property "Sheetname" "")
    (attr smd)
    (fp_text reference "J16" (at -4.5 6.88 180) (layer "F.SilkS")
      (effects (font (size 0.7 0.7) (thickness 0.15)) (justify left bottom))
    )
    (fp_text value "Conn_SMA_RF2-143-T-17-50-G" (at 0 9.24 90) (layer "F.Fab")
      (effects (font (size 0.7 0.7) (thickness 0.15)) (justify left bottom))
    )
    (fp_text user "License: Apache-2.0" (at -4.5 12.44 90) (layer "F.Fab") hide
      (effects (font (size 0.7 0.7) (thickness 0.15)) (justify left bottom))
    )
    (fp_text user "Author: Antmicro" (at -4.5 11.24 90) (layer "F.Fab") hide
      (effects (font (size 0.7 0.7) (thickness 0.15)) (justify left bottom))
    )
    (fp_text user "${REFERENCE}" (at -4.5 13.64 90) (layer "F.Fab") hide
      (effects (font (size 0.7 0.7) (thickness 0.15)) (justify left bottom))
    )
    (fp_rect (start -3.995 -7.53) (end 3.995 7.53) (layer "B.CrtYd") (width 0.05) (fill none))
    (fp_rect (start -3.995 -7.53) (end 3.995 7.53) (layer "F.CrtYd") (width 0.05) (fill none))
    (fp_line (start 3.174 2.654) (end -3.15 2.654) (layer "F.Fab") (width 0.15))
    (fp_line (start -3.174 6.455) (end -3.174 1.504) (layer "F.Fab") (width 0.15))
    (fp_line (start -2.65 -6.375) (end -2.65 1.504) (layer "F.Fab") (width 0.15))
    (fp_line (start 3.174 6.455) (end 3.174 1.504) (layer "F.Fab") (width 0.15))
    (fp_line (start 0.38 2.654) (end 0.375 6.455) (layer "F.Fab") (width 0.15))
    (fp_line (start 3.174 6.455) (end 2.375 6.455) (layer "F.Fab") (width 0.15))
    (fp_line (start 2.65 -6.375) (end 2.65 1.504) (layer "F.Fab") (width 0.15))
    (fp_line (start 2.65 -6.375) (end -2.65 -6.375) (layer "F.Fab") (width 0.15))
    (fp_line (start -0.38 2.654) (end -0.38 6.455) (layer "F.Fab") (width 0.15))
    (fp_line (start 2.375 6.455) (end 2.375 2.678) (layer "F.Fab") (width 0.15))
    (fp_line (start 3.174 1.504) (end -3.174 1.504) (layer "F.Fab") (width 0.15))
    (fp_line (start 0.375 6.455) (end -0.38 6.455) (layer "F.Fab") (width 0.15))
    (fp_line (start -2.375 2.678) (end -2.375 6.455) (layer "F.Fab") (width 0.15))
    (fp_line (start -2.375 6.455) (end -3.174 6.455) (layer "F.Fab") (width 0.15))
    (pad "1" smd rect (at 0.007 4.955 90) (size 2.29 4.191) (layers "F.Cu" "F.Paste" "F.Mask")
      (net 10 "Net-(J16-Pad1)") (pinfunction "1") (pintype "passive"))
    (pad "2" smd rect (at -2.975 4.955 90) (size 1.45 4.191) (layers "F.Cu" "F.Paste" "F.Mask")
      (net 2 "GND") (pinfunction "2") (pintype "passive"))
    (pad "2" smd rect (at 2.975 4.955 90) (size 1.45 4.191) (layers "B.Cu" "B.Paste" "B.Mask")
      (net 2 "GND") (pinfunction "2") (pintype "passive"))
    (pad "2" smd rect (at -2.975 4.955 90) (size 1.45 4.191) (layers "B.Cu" "B.Paste" "B.Mask")
      (net 2 "GND") (pinfunction "2") (pintype "passive"))
    (pad "2" smd rect (at 2.975 4.955 90) (size 1.45 4.191) (layers "F.Cu" "F.Paste" "F.Mask")
      (net 2 "GND") (pinfunction "2") (pintype "passive"))
  )
	(footprint "si-simulation-test-board-footprints:RF_SMA_BoardEdge_RF2-143-T-17-50-G" (layer "F.Cu")
    (tedit 64FEFFC5)
    (at 91.32 65.999499 90)
    (descr "RF SMA SMD board edge connector")
    (property "Author" "Antmicro")
    (property "License" "Apache-2.0")
    (property "MPN" "RF2-143-T-17-50-G")
    (property "Manufacturer" "ADAM TECH")
    (property "Sheetfile" "si-simulation-test-board.kicad_sch")
    (property "Sheetname" "")
    (attr smd)
    (fp_text reference "J4" (at -4.5 6.88 180) (layer "F.SilkS")
      (effects (font (size 0.7 0.7) (thickness 0.15)) (justify left bottom))
    )
    (fp_text value "Conn_SMA_RF2-143-T-17-50-G" (at 0 9.24 90) (layer "F.Fab")
      (effects (font (size 0.7 0.7) (thickness 0.15)) (justify left bottom))
    )
    (fp_text user "Author: Antmicro" (at -4.5 11.24 90) (layer "F.Fab") hide
      (effects (font (size 0.7 0.7) (thickness 0.15)) (justify left bottom))
    )
    (fp_text user "${REFERENCE}" (at -4.5 13.64 90) (layer "F.Fab") hide
      (effects (font (size 0.7 0.7) (thickness 0.15)) (justify left bottom))
    )
    (fp_text user "License: Apache-2.0" (at -4.5 12.44 90) (layer "F.Fab") hide
      (effects (font (size 0.7 0.7) (thickness 0.15)) (justify left bottom))
    )
    (fp_rect (start -3.995 -7.53) (end 3.995 7.53) (layer "B.CrtYd") (width 0.05) (fill none))
    (fp_rect (start -3.995 -7.53) (end 3.995 7.53) (layer "F.CrtYd") (width 0.05) (fill none))
    (fp_line (start -2.65 -6.375) (end -2.65 1.504) (layer "F.Fab") (width 0.15))
    (fp_line (start 3.174 1.504) (end -3.174 1.504) (layer "F.Fab") (width 0.15))
    (fp_line (start 2.65 -6.375) (end -2.65 -6.375) (layer "F.Fab") (width 0.15))
    (fp_line (start -2.375 6.455) (end -3.174 6.455) (layer "F.Fab") (width 0.15))
    (fp_line (start 3.174 2.654) (end -3.15 2.654) (layer "F.Fab") (width 0.15))
    (fp_line (start -2.375 2.678) (end -2.375 6.455) (layer "F.Fab") (width 0.15))
    (fp_line (start 2.65 -6.375) (end 2.65 1.504) (layer "F.Fab") (width 0.15))
    (fp_line (start 2.375 6.455) (end 2.375 2.678) (layer "F.Fab") (width 0.15))
    (fp_line (start -3.174 6.455) (end -3.174 1.504) (layer "F.Fab") (width 0.15))
    (fp_line (start 3.174 6.455) (end 2.375 6.455) (layer "F.Fab") (width 0.15))
    (fp_line (start 0.38 2.654) (end 0.375 6.455) (layer "F.Fab") (width 0.15))
    (fp_line (start 3.174 6.455) (end 3.174 1.504) (layer "F.Fab") (width 0.15))
    (fp_line (start 0.375 6.455) (end -0.38 6.455) (layer "F.Fab") (width 0.15))
    (fp_line (start -0.38 2.654) (end -0.38 6.455) (layer "F.Fab") (width 0.15))
    (pad "1" smd rect (at 0.007 4.955 90) (size 2.29 4.191) (layers "F.Cu" "F.Paste" "F.Mask")
      (net 2 "GND") (pinfunction "1") (pintype "passive"))
    (pad "2" smd rect (at 2.975 4.955 90) (size 1.45 4.191) (layers "F.Cu" "F.Paste" "F.Mask")
      (net 2 "GND") (pinfunction "2") (pintype "passive"))
    (pad "2" smd rect (at 2.975 4.955 90) (size 1.45 4.191) (layers "B.Cu" "B.Paste" "B.Mask")
      (net 2 "GND") (pinfunction "2") (pintype "passive"))
    (pad "2" smd rect (at -2.975 4.955 90) (size 1.45 4.191) (layers "F.Cu" "F.Paste" "F.Mask")
      (net 2 "GND") (pinfunction "2") (pintype "passive"))
    (pad "2" smd rect (at -2.975 4.955 90) (size 1.45 4.191) (layers "B.Cu" "B.Paste" "B.Mask")
      (net 2 "GND") (pinfunction "2") (pintype "passive"))
  )
)
